#ISCELL
  pure_quanta quanta_title_block_c *
  *
#CELL
  pure_quanta sn74lvc2g07dckr *
  page61_i17
#ISCELL
  pure_quanta_power universal_gnd *
  page61_i18
#ISCELL
  pure_quanta_power universal_power *
  page61_i19
#CELL
  pure_quanta q_cap *
  page61_i20
#ISCELL
  standard offpage *
  page61_i21
#ISCELL
  standard offpage *
  page61_i22
#ISCELL
  standard offpage *
  page61_i23
#ISCELL
  standard offpage *
  page61_i24
#ISCELL
  pure_quanta_power universal_gnd *
  page61_i25
#CELL
  pure_quanta q_res *
  page61_i26
#CELL
  pure_quanta q_res *
  page61_i27
#ISCELL
  pure_quanta_power universal_power *
  page61_i28
#ISCELL
  standard offpage *
  page61_i29
#ISCELL
  standard offpage *
  page61_i30
